# S9S_MB_2U (Grand Teton) — schematic netlist excerpt (pin names and nets, part order shuffled) for the footprints in the layout excerpt that follows; sources: Cadence DE-HDL packaged netlist, KiCad conversion of 03242023_DA0F0TMBIJ0_F0T_Motherboard_J_brd_V01_OCP.brd

R613  Q_RES  10K 1% CHIP  pkg 0402LF  page 199 : A = P3V3_AUX ; B = FM_JTAG_ODT_DISABLE
R916  Q_RES  0 5% CHIP  pkg 0402LF  page 185 : A = SPI_PCH_IO1 ; B = SPI_SYS_MISO

(kicad_pcb
	(version 20260206)
	(generator "pcbnew")
	(generator_version "10.0")
	(general
		(thickness 1.6)
		(legacy_teardrops no)
	)
	(paper "A4")
	(title_block
		(title "03242023_DA0F0TMBIJ0_F0T_Motherboard_J_brd_V01_OCP.brd")
		(comment 1 "Grand Teton / footprints 4364-4365 of 6105")
	)
	(layers
		(0 "F.Cu" signal "TOP")
		(4 "In1.Cu" signal "GND")
		(6 "In2.Cu" signal "IN1")
		(8 "In3.Cu" signal "GND1")
		(10 "In4.Cu" signal "IN2")
		(12 "In5.Cu" signal "GND2")
		(14 "In6.Cu" signal "IN3")
		(16 "In7.Cu" signal "GND3")
		(18 "In8.Cu" signal "VCC")
		(20 "In9.Cu" signal "VCC1")
		(22 "In10.Cu" signal "GND4")
		(24 "In11.Cu" signal "IN4")
		(26 "In12.Cu" signal "GND5")
		(28 "In13.Cu" signal "IN5")
		(30 "In14.Cu" signal "GND6")
		(32 "In15.Cu" signal "IN6")
		(34 "In16.Cu" signal "GND7")
		(2 "B.Cu" signal "BOTTOM")
		(9 "F.Adhes" user "F.Adhesive")
		(11 "B.Adhes" user "B.Adhesive")
		(13 "F.Paste" user "Package Geometry/Pastemask Top")
		(15 "B.Paste" user "Package Geometry/Pastemask Bottom")
		(5 "F.SilkS" user "Ref Des/Silkscreen Top")
		(7 "B.SilkS" user "Ref Des/Silkscreen Bottom")
		(1 "F.Mask" user "Board Geometry/Soldermask Top")
		(3 "B.Mask" user "Board Geometry/Soldermask Bottom")
		(17 "Dwgs.User" user "User.Drawings")
		(19 "Cmts.User" user "User.Comments")
		(21 "Eco1.User" user "User.Eco1")
		(23 "Eco2.User" user "User.Eco2")
		(25 "Edge.Cuts" user "Board Geometry/Outline")
		(27 "Margin" user)
		(31 "F.CrtYd" user "Package Geometry/Place Bound Top")
		(29 "B.CrtYd" user "Package Geometry/Place Bound Bottom")
		(35 "F.Fab" user "Ref Des/Assembly Top")
		(33 "B.Fab" user "Ref Des/Assembly Bottom")
	)
	(footprint ""
		(layer "B.Cu")
		(at 336.167222 -33.20542 90)
		(property "Reference" "R916"
			(at 0 0 90)
			(layer "B.SilkS")
			(hide yes)
			(effects
				(font
					(size 1.27 1.27)
				)
				(justify mirror)
			)
		)
		(property "Value" ""
			(at 0 0 90)
			(layer "B.Fab")
			(effects
				(font
					(size 1.27 1.27)
				)
				(justify mirror)
			)
		)
		(duplicate_pad_numbers_are_jumpers no)
		(fp_line
			(start 0.7874 -0.4064)
			(end -0.7874 -0.4064)
			(stroke
				(width 0.1524)
				(type default)
			)
			(layer "B.SilkS")
		)
		(fp_line
			(start -0.7874 -0.4064)
			(end -0.7874 0.4064)
			(stroke
				(width 0.1524)
				(type default)
			)
			(layer "B.SilkS")
		)
		(fp_line
			(start 0.7874 0.4064)
			(end 0.7874 -0.4064)
			(stroke
				(width 0.1524)
				(type default)
			)
			(layer "B.SilkS")
		)
		(fp_line
			(start -0.7874 0.4064)
			(end 0.7874 0.4064)
			(stroke
				(width 0.1524)
				(type default)
			)
			(layer "B.SilkS")
		)
		(fp_line
			(start 0.67945 -0.305054)
			(end 0.12065 -0.305054)
			(stroke
				(width 0.1)
				(type default)
			)
			(layer "B.Fab")
		)
		(fp_line
			(start 0.12065 -0.305054)
			(end 0.12065 -0.2794)
			(stroke
				(width 0.1)
				(type default)
			)
			(layer "B.Fab")
		)
		(fp_line
			(start -0.12065 -0.3048)
			(end -0.67945 -0.3048)
			(stroke
				(width 0.1)
				(type default)
			)
			(layer "B.Fab")
		)
		(fp_line
			(start -0.67945 -0.3048)
			(end -0.67945 0.3048)
			(stroke
				(width 0.1)
				(type default)
			)
			(layer "B.Fab")
		)
		(fp_line
			(start 0.12065 -0.2794)
			(end -0.12065 -0.2794)
			(stroke
				(width 0.1)
				(type default)
			)
			(layer "B.Fab")
		)
		(fp_line
			(start -0.12065 -0.2794)
			(end -0.12065 -0.3048)
			(stroke
				(width 0.1)
				(type default)
			)
			(layer "B.Fab")
		)
		(fp_line
			(start 0.12065 0.2794)
			(end 0.12065 0.3048)
			(stroke
				(width 0.1)
				(type default)
			)
			(layer "B.Fab")
		)
		(fp_line
			(start -0.120396 0.2794)
			(end 0.12065 0.2794)
			(stroke
				(width 0.1)
				(type default)
			)
			(layer "B.Fab")
		)
		(fp_line
			(start 0.67945 0.3048)
			(end 0.67945 -0.305054)
			(stroke
				(width 0.1)
				(type default)
			)
			(layer "B.Fab")
		)
		(fp_line
			(start 0.12065 0.3048)
			(end 0.67945 0.3048)
			(stroke
				(width 0.1)
				(type default)
			)
			(layer "B.Fab")
		)
		(fp_line
			(start -0.120396 0.3048)
			(end -0.120396 0.2794)
			(stroke
				(width 0.1)
				(type default)
			)
			(layer "B.Fab")
		)
		(fp_line
			(start -0.67945 0.3048)
			(end -0.120396 0.3048)
			(stroke
				(width 0.1)
				(type default)
			)
			(layer "B.Fab")
		)
		(pad "1" smd circle
			(at 0.40005 0 270)
			(size 0 0)
			(layers "B.Cu" "B.Mask" "B.Paste")
			(net "SPI_PCH_IO1")
		)
		(pad "2" smd circle
			(at -0.40005 0 270)
			(size 0 0)
			(layers "B.Cu" "B.Mask" "B.Paste")
			(net "SPI_SYS_MISO")
		)
	)
	(footprint ""
		(layer "B.Cu")
		(at 326.00519 -28.84297 -90)
		(property "Reference" "R613"
			(at 0 0 90)
			(layer "B.SilkS")
			(hide yes)
			(effects
				(font
					(size 1.27 1.27)
				)
				(justify mirror)
			)
		)
		(property "Value" ""
			(at 0 0 90)
			(layer "B.Fab")
			(effects
				(font
					(size 1.27 1.27)
				)
				(justify mirror)
			)
		)
		(duplicate_pad_numbers_are_jumpers no)
		(fp_line
			(start -0.7874 0.4064)
			(end 0.7874 0.4064)
			(stroke
				(width 0.1524)
				(type default)
			)
			(layer "B.SilkS")
		)
		(fp_line
			(start 0.7874 0.4064)
			(end 0.7874 -0.4064)
			(stroke
				(width 0.1524)
				(type default)
			)
			(layer "B.SilkS")
		)
		(fp_line
			(start -0.7874 -0.4064)
			(end -0.7874 0.4064)
			(stroke
				(width 0.1524)
				(type default)
			)
			(layer "B.SilkS")
		)
		(fp_line
			(start 0.7874 -0.4064)
			(end -0.7874 -0.4064)
			(stroke
				(width 0.1524)
				(type default)
			)
			(layer "B.SilkS")
		)
		(fp_line
			(start -0.67945 0.3048)
			(end -0.120396 0.3048)
			(stroke
				(width 0.1)
				(type default)
			)
			(layer "B.Fab")
		)
		(fp_line
			(start -0.120396 0.3048)
			(end -0.120396 0.2794)
			(stroke
				(width 0.1)
				(type default)
			)
			(layer "B.Fab")
		)
		(fp_line
			(start 0.12065 0.3048)
			(end 0.67945 0.3048)
			(stroke
				(width 0.1)
				(type default)
			)
			(layer "B.Fab")
		)
		(fp_line
			(start 0.67945 0.3048)
			(end 0.67945 -0.305054)
			(stroke
				(width 0.1)
				(type default)
			)
			(layer "B.Fab")
		)
		(fp_line
			(start -0.120396 0.2794)
			(end 0.12065 0.2794)
			(stroke
				(width 0.1)
				(type default)
			)
			(layer "B.Fab")
		)
		(fp_line
			(start 0.12065 0.2794)
			(end 0.12065 0.3048)
			(stroke
				(width 0.1)
				(type default)
			)
			(layer "B.Fab")
		)
		(fp_line
			(start -0.12065 -0.2794)
			(end -0.12065 -0.3048)
			(stroke
				(width 0.1)
				(type default)
			)
			(layer "B.Fab")
		)
		(fp_line
			(start 0.12065 -0.2794)
			(end -0.12065 -0.2794)
			(stroke
				(width 0.1)
				(type default)
			)
			(layer "B.Fab")
		)
		(fp_line
			(start -0.67945 -0.3048)
			(end -0.67945 0.3048)
			(stroke
				(width 0.1)
				(type default)
			)
			(layer "B.Fab")
		)
		(fp_line
			(start -0.12065 -0.3048)
			(end -0.67945 -0.3048)
			(stroke
				(width 0.1)
				(type default)
			)
			(layer "B.Fab")
		)
		(fp_line
			(start 0.12065 -0.305054)
			(end 0.12065 -0.2794)
			(stroke
				(width 0.1)
				(type default)
			)
			(layer "B.Fab")
		)
		(fp_line
			(start 0.67945 -0.305054)
			(end 0.12065 -0.305054)
			(stroke
				(width 0.1)
				(type default)
			)
			(layer "B.Fab")
		)
		(pad "1" smd circle
			(at 0.40005 0 90)
			(size 0 0)
			(layers "B.Cu" "B.Mask" "B.Paste")
			(net "P3V3_AUX")
		)
		(pad "2" smd circle
			(at -0.40005 0 90)
			(size 0 0)
			(layers "B.Cu" "B.Mask" "B.Paste")
			(net "FM_JTAG_ODT_DISABLE")
		)
	)
)
